FILE_TYPE = CONNECTIVITY;
{Allegro Design Entry HDL 16.6-p007 (v16-6-112F) 10/10/2012}
"PAGE_NUMBER" = 55;
0"NC";
1"GND\g";
2"GND\g";
3"P3V3_STBY\g";
4"P3V3_STBY\g";
5"PVCCIO_CPU1\g";
6"PVCCIO_CPU1\g";
7"A_CPU1_PE3_RBIAS";
8"TP_XDP_CPU1_OBSDATA_B2_MBP4_N";
9"TP_XDP_CPU1_OBSDATA_B0_MBP2_N";
10"TP_XDP_CPU1_OBSDATA_B3_MBP5_N";
11"TP_XDP_CPU1_OBSDATA_B1_MBP3_N";
12"A_CPU1_GHJ_RCOMP2";
13"A_CPU1_UPI01_RBIAS";
14"A_CPU1_KLM_RCOMP0";
15"A_CPU1_KLM_RCOMP1";
16"A_CPU1_KLM_RCOMP2";
17"A_CPU1_GHJ_RCOMP0";
18"A_CPU1_GHJ_RCOMP1";
19"A_CPU1_PE012_RBIAS";
20"A_CPU1_UPI2_RBIAS";
21"A_CPU1_MCP01_RBIAS";
22"XDP_CPU1_TDI";
23"XDP_CPU_TCK0";
24"XDP_CPU_TMS";
25"XDP_CPU_TRST_N";
26"CLK_100M_CPU1_BCLK2_DN";
27"CLK_100M_CPU1_BCLK2_DP";
28"M_H_CPU_VREF";
29"M_J_CPU_VREF";
30"M_L_CPU_VREF";
31"M_M_CPU_VREF";
32"XDP_CPU_OBSFN_B1_MBP7_N";
33"XDP_CPU_OBSFN_B0_MBP6_N";
34"SMB_PIROM_CPU1_SCL";
35"SMB_PIROM_CPU1_SDA";
36"XDP_CPU_MBP1_N";
37"XDP_CPU_MBP0_N";
38"CLK_100M_CPU1_BCLK0_DP";
39"CLK_100M_CPU1_BCLK0_DN";
40"CLK_100M_CPU1_BCLK1_DN";
41"CLK_100M_CPU1_BCLK1_DP";
42"PWRGD_CPU1_DRAMPWROK_GHJ_G";
43"PWRGD_CPU1_DRAMPWROK_KLM_G";
44"M_KLM_RST_N";
45"M_GHJ_RST_N";
46"H_CPU1_MEMGHJ_MEMHOT_G_N";
47"H_CPU1_MEMKLM_MEMHOT_G_N";
48"M_K_CPU_VREF";
49"M_G_CPU_VREF";
50"SMB_CPU1_PE_HP_GTL_SCL";
51"SMB_CPU1_PE_HP_GTL_SDA";
52"SMB_DDR_KLM_SDA_G_R";
53"SMB_DDR_GHJ_SDA_G_R";
54"SMB_DDR_KLM_SCL_G_R";
55"SMB_DDR_GHJ_SCL_G_R";
56"SVID_CLK0_CPU1";
57"SVID_CLK1_CPU1";
58"SVID_ALERT1_CPU1_N";
59"H_PM_SYNC_GTL_R2";
60"SVID_DIO0_CPU1";
61"SVID_ALERT0_CPU1_N";
62"H_PMSYNC_CLK_24M_CPU1";
63"SVID_DIO1_CPU1";
64"TP_CPU1_SOCKET_ID_2";
65"TP_CPU1_PROC_DIS_G_N";
66"TP_CPU1_NMI";
67"RST_CPU1_G_N";
68"H_PM_SYNC_GTL";
69"PU_CPU1_EAR_N";
70"H_PMSYNC_CLK_24M";
71"PU_CPU1_SOCKET_ID_1";
72"PU_CPU1_SOCKET_ID_0";
73"PU_CPU1_TSC_SYNC";
74"PU_CPU1_LEGACY_SKT";
75"PD_CPU1_KSFC_DIS";
76"PD_CPU1_TEST14";
77"PD_CPU1_TEST13";
78"PD_CPU1_TEST12";
79"XDP_CPU_PREQ_N";
80"XDP_CPU_PRDY_N";
81"FM_CPU1_SM_WP";
82"PD_PIROM_CPU1_ADDR2";
83"PD_PIROM_CPU1_ADDR1";
84"PU_PIROM_CPU1_ADDR0";
85"PECI_CPU_G";
86"H_CPU1_CATERR_G_N";
87"H_CPU1_ERR2_G_N";
88"H_CPU1_MSMI_G_N";
89"H_CPU1_ERR0_G_N";
90"H_CPU1_ERR1_G_N";
91"H_CPU1_PROCHOT_G_N";
92"H_CPU1_THERMTRIP_G_N";
93"PU_CPU1_SAFE_MODE_BOOT";
94"H_CPU1_BMCINIT";
95"PU_CPU1_FRMAGENT";
96"PD_CPU1_TXT_PLTEN";
97"PU_CPU1_TXT_AGENT";
98"H_CPU1_FAST_WAKE_N";
99"PD_CPU1_BIST_ENABLE";
100"XDP_CPU1_TDO";
101"PWRGD_CPU1_G";
102"FM_CPU1_SKTOCC_LVT3_N";
103"FM_CPU1_PKGID1";
104"FM_CPU1_PKGID2";
105"FM_CPU1_PKGID0";
106"SVID_CLK1_CPU1_R";
107"SVID_CLK0_CPU1_R";
108"FM_CPU1_PROC_ID1";
109"FM_CPU1_PROC_ID0";
110"SVID_DIO0_CPU1_R";
111"SVID_ALERT0_CPU1_R_N";
112"SVID_ALERT1_CPU1_R_N";
113"SVID_DIO1_CPU1_R";
%"RES"
"2","(6575,2650)","2","mstr_discrete","I115";
;
CDS_SEC"1"
ROOM"CPU1"
CDS_LOCATION"R7P19"
SEC"1"
BOM_COST"PROC_SOCKET"
CDS_LIB"mstr_discrete"
SEC_TYPE"0402"
WATTAGE"1/16W"
MATERIAL"CHIP"
PACK_TYPE"0402"
TOLERANCE"1%"
VALUE"100.0"
PART_NUMBER"G21796-017"
LOCATION"R7P19";
"A"
$PN"1"12;
"B"
$PN"2"1;
%"RES"
"2","(7700,2525)","2","mstr_discrete","I116";
;
CDS_SEC"1"
ROOM"CPU1"
CDS_LOCATION"R3D1"
SEC"1"
BOM_COST"PROC_SOCKET"
CDS_LIB"mstr_discrete"
SEC_TYPE"0402"
WATTAGE"1/16W"
MATERIAL"CHIP"
PACK_TYPE"0402"
TOLERANCE"1%"
VALUE"90.9"
PART_NUMBER"G21796-365"
LOCATION"R3D1";
"A"
$PN"1"14;
"B"
$PN"2"1;
%"RES"
"2","(7475,2575)","2","mstr_discrete","I117";
;
CDS_SEC"1"
ROOM"CPU1"
CDS_LOCATION"R3D2"
SEC"1"
BOM_COST"PROC_SOCKET"
CDS_LIB"mstr_discrete"
SEC_TYPE"0402"
WATTAGE"1/16W"
MATERIAL"CHIP"
PACK_TYPE"0402"
TOLERANCE"1%"
VALUE"90.9"
PART_NUMBER"G21796-365"
LOCATION"R3D2";
"A"
$PN"1"15;
"B"
$PN"2"1;
%"RES"
"2","(7250,2575)","2","mstr_discrete","I118";
;
CDS_SEC"1"
ROOM"CPU1"
CDS_LOCATION"R3D3"
SEC"1"
BOM_COST"PROC_SOCKET"
CDS_LIB"mstr_discrete"
SEC_TYPE"0402"
WATTAGE"1/16W"
MATERIAL"CHIP"
PACK_TYPE"0402"
TOLERANCE"1%"
VALUE"100.0"
PART_NUMBER"G21796-017"
LOCATION"R3D3";
"A"
$PN"1"16;
"B"
$PN"2"1;
%"RES"
"2","(7025,2575)","2","mstr_discrete","I119";
;
CDS_SEC"1"
ROOM"CPU1"
CDS_LOCATION"R7P16"
SEC"1"
BOM_COST"PROC_SOCKET"
CDS_LIB"mstr_discrete"
SEC_TYPE"0402"
WATTAGE"1/16W"
MATERIAL"CHIP"
PACK_TYPE"0402"
TOLERANCE"1%"
VALUE"90.9"
PART_NUMBER"G21796-365"
LOCATION"R7P16";
"A"
$PN"1"17;
"B"
$PN"2"1;
%"GND"
"1","(6575,2225)","0","mstr_symbols","I121";
;
HDL_POWER"GND"
BODY_TYPE"PLUMBING"
CDS_LIB"mstr_symbols"
SIZE"1B"
VOLTAGE"0.0V";
"A\NAC"1;
%"GND"
"1","(6575,1025)","0","mstr_symbols","I122";
;
HDL_POWER"GND"
BODY_TYPE"PLUMBING"
SIZE"1B"
CDS_LIB"mstr_symbols"
VOLTAGE"0.0V";
"A\NAC"2;
%"RES"
"2","(6575,1425)","2","mstr_discrete","I123";
;
CDS_SEC"1"
ROOM"CPU1"
CDS_LOCATION"R7P8"
SEC"1"
BOM_COST"PROC_SOCKET"
SEC_TYPE"0402"
CDS_LIB"mstr_discrete"
WATTAGE"1/16W"
MATERIAL"CHIP"
PACK_TYPE"0402"
TOLERANCE"1%"
VALUE"49.9"
PART_NUMBER"G21796-047"
LOCATION"R7P8";
"A"
$PN"1"7;
"B"
$PN"2"2;
%"RES"
"2","(6775,1425)","2","mstr_discrete","I124";
;
CDS_SEC"1"
ROOM"CPU1"
CDS_LOCATION"R7P10"
SEC"1"
BOM_COST"PROC_SOCKET"
CDS_LIB"mstr_discrete"
SEC_TYPE"0402"
WATTAGE"1/16W"
MATERIAL"CHIP"
PACK_TYPE"0402"
TOLERANCE"1%"
VALUE"49.9"
PART_NUMBER"G21796-047"
LOCATION"R7P10";
"A"
$PN"1"19;
"B"
$PN"2"2;
%"RES"
"2","(7000,1425)","2","mstr_discrete","I125";
;
CDS_SEC"1"
ROOM"CPU1"
CDS_LOCATION"R3D19"
SEC"1"
BOM_COST"PROC_SOCKET"
CDS_LIB"mstr_discrete"
SEC_TYPE"0402"
WATTAGE"1/16W"
MATERIAL"CHIP"
PACK_TYPE"0402"
TOLERANCE"1%"
VALUE"49.9"
PART_NUMBER"G21796-047"
LOCATION"R3D19";
"A"
$PN"1"13;
"B"
$PN"2"2;
%"RES"
"2","(7200,1425)","2","mstr_discrete","I126";
;
CDS_SEC"1"
ROOM"CPU1"
CDS_LOCATION"R7P11"
SEC"1"
BOM_COST"PROC_SOCKET"
CDS_LIB"mstr_discrete"
SEC_TYPE"0402"
WATTAGE"1/16W"
MATERIAL"CHIP"
PACK_TYPE"0402"
TOLERANCE"1%"
VALUE"49.9"
PART_NUMBER"G21796-047"
LOCATION"R7P11";
"A"
$PN"1"20;
"B"
$PN"2"2;
%"RES"
"2","(6800,2650)","2","mstr_discrete","I140";
;
CDS_SEC"1"
ROOM"CPU1"
CDS_LOCATION"R7P17"
SEC"1"
BOM_COST"PROC_SOCKET"
CDS_LIB"mstr_discrete"
SEC_TYPE"0402"
WATTAGE"1/16W"
MATERIAL"CHIP"
PACK_TYPE"0402"
TOLERANCE"1%"
VALUE"90.9"
PART_NUMBER"G21796-365"
LOCATION"R7P17";
"A"
$PN"1"18;
"B"
$PN"2"1;
%"SOCKET_P_MECH_A"
"1","(6875,4000)","0","chpset_lib","I152";
;
ROOM"CPU1"
CDS_LOCATION"XRU2"
BOM_COST"PROC_SOCKET"
CDS_LIB"chpset_lib"
SKT_NUMBER"P0"
MATERIAL"PLASTIC"
PACK_TYPE"RIGHT"
PART_NUMBER"H37604-101"
LOCATION"XRU2";
%"SOCKET_P_MECH_A"
"1","(6875,3725)","0","chpset_lib","I153";
;
ROOM"CPU1"
CDS_LOCATION"XLU2"
BOM_COST"PROC_SOCKET"
CDS_LIB"chpset_lib"
SKT_NUMBER"P0"
MATERIAL"PLASTIC"
PACK_TYPE"LEFT"
PART_NUMBER"H37604-201"
LOCATION"XLU2";
%"RES"
"2","(7400,1425)","2","mstr_discrete","I155";
;
CDS_SEC"1"
ROOM"CPU1"
CDS_LOCATION"R3D4"
SEC"1"
BOM_COST"PROC_SOCKET"
SEC_TYPE"0402"
CDS_LIB"mstr_discrete"
WATTAGE"1/16W"
MATERIAL"CHIP"
PACK_TYPE"0402"
TOLERANCE"1%"
VALUE"49.9"
PART_NUMBER"G21796-047"
LOCATION"R3D4";
"A"
$PN"1"21;
"B"
$PN"2"2;
%"RES"
"1","(11925,3850)","0","mstr_discrete","I156";
;
CDS_SEC"1"
ROOM"CPU1"
CDS_LOCATION"R7P26"
SEC"1"
BOM_COST"PROC_SOCKET"
CDS_LIB"mstr_discrete"
SEC_TYPE"0402"
WATTAGE"1/16W"
MATERIAL"CHIP"
PACK_TYPE"0402"
TOLERANCE"1%"
VALUE"49.9"
PART_NUMBER"G21796-047"
LOCATION"R7P26";
"B"
$PN"2"70;
"A"
$PN"1"62;
%"RES"
"2","(12875,2350)","0","mstr_discrete","I157";
;
CDS_SEC"1"
ROOM"CPU1"
CDS_LOCATION"R8N1"
SEC"1"
BOM_COST"PROC_SOCKET"
CDS_LIB"mstr_discrete"
SEC_TYPE"0402"
WATTAGE"1/16W"
MATERIAL"CHIP"
PACK_TYPE"0402"
TOLERANCE"1%"
VALUE"1.8K"
PART_NUMBER"G21796-336"
LOCATION"R8N1";
"A"
$PN"1"3;
"B"
$PN"2"108;
%"RES"
"2","(13075,2350)","0","mstr_discrete","I158";
;
CDS_SEC"1"
ROOM"CPU1"
CDS_LOCATION"R8N4"
SEC"1"
BOM_COST"PROC_SOCKET"
CDS_LIB"mstr_discrete"
SEC_TYPE"0402"
WATTAGE"1/16W"
MATERIAL"CHIP"
PACK_TYPE"0402"
TOLERANCE"1%"
VALUE"1.8K"
PART_NUMBER"G21796-336"
LOCATION"R8N4";
"A"
$PN"1"3;
"B"
$PN"2"109;
%"RES"
"2","(13275,2350)","0","mstr_discrete","I159";
;
CDS_SEC"1"
ROOM"CPU1"
CDS_LOCATION"R8N3"
SEC"1"
BOM_COST"PROC_SOCKET"
CDS_LIB"mstr_discrete"
SEC_TYPE"0402"
WATTAGE"1/16W"
MATERIAL"CHIP"
PACK_TYPE"0402"
TOLERANCE"1%"
VALUE"10.0K"
PART_NUMBER"G21796-016"
LOCATION"R8N3";
"A"
$PN"1"3;
"B"
$PN"2"104;
%"RES"
"2","(13475,2350)","0","mstr_discrete","I160";
;
CDS_SEC"1"
ROOM"CPU1"
CDS_LOCATION"R8N5"
SEC"1"
BOM_COST"PROC_SOCKET"
CDS_LIB"mstr_discrete"
SEC_TYPE"0402"
WATTAGE"1/16W"
MATERIAL"CHIP"
PACK_TYPE"0402"
TOLERANCE"1%"
VALUE"10.0K"
PART_NUMBER"G21796-016"
LOCATION"R8N5";
"A"
$PN"1"3;
"B"
$PN"2"103;
%"RES"
"2","(13675,2350)","0","mstr_discrete","I161";
;
CDS_SEC"1"
ROOM"CPU1"
CDS_LOCATION"R8N2"
SEC"1"
BOM_COST"PROC_SOCKET"
CDS_LIB"mstr_discrete"
SEC_TYPE"0402"
VALUE"10.0K"
MATERIAL"CHIP"
PACK_TYPE"0402"
WATTAGE"1/16W"
TOLERANCE"1%"
PART_NUMBER"G21796-016"
LOCATION"R8N2";
"A"
$PN"1"3;
"B"
$PN"2"105;
%"P3V3_STBY"
"1","(13675,2700)","0","mstr_symbols","I162";
;
HDL_POWER"P3V3_STBY"
BODY_TYPE"PLUMBING"
SIZE"1B"
CDS_LIB"mstr_symbols"
VOLTAGE"3.3V";
"G\NAC"3;
%"P3V3_STBY"
"1","(13275,1325)","0","mstr_symbols","I169";
;
HDL_POWER"P3V3_STBY"
BODY_TYPE"PLUMBING"
CDS_LIB"mstr_symbols"
SIZE"1B"
VOLTAGE"3.3V";
"G\NAC"4;
%"RES"
"1","(11800,3900)","0","mstr_discrete","I170";
;
CDS_SEC"1"
ROOM"CPU1"
CDS_LOCATION"R7P25"
SEC"1"
BOM_COST"PROC_SOCKET"
CDS_LIB"mstr_discrete"
SEC_TYPE"0402"
WATTAGE"1/16W"
MATERIAL"CHIP"
PACK_TYPE"0402"
TOLERANCE"1%"
VALUE"49.9"
PART_NUMBER"G21796-047"
LOCATION"R7P25";
"B"
$PN"2"68;
"A"
$PN"1"59;
%"SKX_EXT_B"
"1","(10225,2500)","0","chpset_lib","I172";
;
CDS_SEC"1"
ROOM"CPU1"
CDS_LOCATION"U2D1"
SEC"1"
CDS_LIB"chpset_lib"
SEC_TYPE"BGA1"
PACK_TYPE"BGA1"
MATERIAL"IC"
PART_NUMBER"TBD"
LOCATION"U2D1";
"UPI2_RBIAS<0>"
$PN"CL28"20;
"UPI2_RBIAS<1>"
$PN"CK29"20;
"UPI01_RBIAS<0>"
$PN"AT29"13;
"UPI01_RBIAS<1>"
$PN"AP29"13;
"TXT_PLTEN"
$PN"AV15"96;
"TXT_AGENT"
$PN"AW18"97;
"TSC_SYNC"
$PN"AM11"73;
"TRST_N"
$PN"Y13"25;
"TMS"
$PN"W14"24;
"THERMTRIP_N"
$PN"AB15"92;
"TEST_15"
$PN"AW14"75;
"TEST_14"
$PN"DC50"76;
"TEST_13"
$PN"DB51"77;
"TEST_12"
$PN"AY19"78;
"TDO"
$PN"AE14"100;
"TDI"
$PN"AC14"22;
"TCK"
$PN"AA14"23;
"SVIDDATA<0>"
$PN"DB45"60;
"SVIDDATA<1>"
$PN"DJ44"63;
"SVIDCLK<0>"
$PN"DC44"56;
"SVIDCLK<1>"
$PN"DG44"57;
"SVIDALERT_N<0>"
$PN"DE44"61;
"SVIDALERT_N<1>"
$PN"DL44"58;
"SOCKET_ID<0>"
$PN"AU22"72;
"SOCKET_ID<1>"
$PN"AU16"71;
"SOCKET_ID<2>"
$PN"AU20"64;
"SM_WP"
$PN"CV59"81;
"SMBDAT"
$PN"CW58"35;
"SMBCLK"
$PN"CT59"34;
"SKTOCC_N"
$PN"AB13"102;
"SAFE_MODE_BOOT"
$PN"AR18"93;
"RESET_N"
$PN"AP21"67;
"PWRGOOD"
$PN"BC24"101;
"PROC_ID<0>"
$PN"CY71"109;
"PROC_ID<1>"
$PN"DB71"108;
"PROCHOT_N"
$PN"AC16"91;
"PROCDIS_N"
$PN"AB17"65;
"PREQ_N"
$PN"AR12"79;
"PRDY_N"
$PN"AG16"80;
"PM_FAST_WAKE_N"
$PN"AF15"98;
"PMSYNC_CLK"
$PN"AT19"62;
"PMSYNC"
$PN"AR14"59;
"PKGID<0>"
$PN"DC72"105;
"PKGID<1>"
$PN"CW72"103;
"PKGID<2>"
$PN"DA72"104;
"PIROM_ADDR<0>"
$PN"CU58"84;
"PIROM_ADDR<1>"
$PN"CV57"83;
"PIROM_ADDR<2>"
$PN"CW56"82;
"PE_HP_SDA"
$PN"AL18"51;
"PE_HP_SCL"
$PN"AM19"50;
"PECI"
$PN"AU12"85;
"PE3_RBIAS<0>"
$PN"CP29"7;
"PE3_RBIAS<1>"
$PN"CR30"7;
"PE012_RBIAS<0>"
$PN"CN30"19;
"PE012_RBIAS<1>"
$PN"CL30"19;
"NMI"
$PN"AP11"66;
"MSMI_N"
$PN"AN20"88;
"MEM_HOT_C345_N"
$PN"AF13"47;
"MEM_HOT_C012_N"
$PN"AH13"46;
"MCP01_RBIAS<0>"
$PN"CU32"21;
"MCP01_RBIAS<1>"
$PN"CT31"21;
"LEGACY_SKT"
$PN"AE20"74;
"FRMAGENT"
$PN"AV17"95;
"ERROR_N<0>"
$PN"AJ12"89;
"ERROR_N<1>"
$PN"AK11"90;
"ERROR_N<2>"
$PN"AL12"87;
"EAR_N"
$PN"AJ14"69;
"DDR5_CAVREF"
$PN"CV61"31;
"DDR4_CAVREF"
$PN"CT61"30;
"DDR3_CAVREF"
$PN"CP61"48;
"DDR345_SPDSDA"
$PN"AD17"52;
"DDR345_SPDSCL"
$PN"AE18"54;
"DDR345_RESET_N"
$PN"DV63"44;
"DDR345_RCOMP<0>"
$PN"DC48"14;
"DDR345_RCOMP<1>"
$PN"DD47"15;
"DDR345_RCOMP<2>"
$PN"DD49"16;
"DDR345_DRAM_PWR_OK"
$PN"CR28"43;
"DDR2_CAVREF"
$PN"AH63"29;
"DDR1_CAVREF"
$PN"AK63"28;
"DDR0_CAVREF"
$PN"AJ64"49;
"DDR012_SPDSDA"
$PN"AF17"53;
"DDR012_SPDSCL"
$PN"AJ18"55;
"DDR012_RESET_N"
$PN"U64"45;
"DDR012_RCOMP<0>"
$PN"Y43"17;
"DDR012_RCOMP<1>"
$PN"AB43"18;
"DDR012_RCOMP<2>"
$PN"AC42"12;
"DDR012_DRAM_PWR_OK"
$PN"AN30"42;
"CATERR_N"
$PN"AL14"86;
"BPM_N<0>"
$PN"AJ10"37;
"BPM_N<1>"
$PN"AH11"36;
"BPM_N<2>"
$PN"AG10"9;
"BPM_N<3>"
$PN"AF11"11;
"BPM_N<4>"
$PN"AA12"8;
"BPM_N<5>"
$PN"Y11"10;
"BPM_N<6>"
$PN"AE12"33;
"BPM_N<7>"
$PN"AC12"32;
"BMCINIT"
$PN"BD23"94;
"BIST_ENABLE"
$PN"BA20"99;
"BCLK2_DP"
$PN"CU26"27;
"BCLK2_DN"
$PN"CT25"26;
"BCLK1_DP"
$PN"CP27"41;
"BCLK1_DN"
$PN"CR26"40;
"BCLK0_DP"
$PN"AW24"38;
"BCLK0_DN"
$PN"AU24"39;
%"RES"
"2","(13275,1100)","0","mstr_discrete","I181";
;
CDS_SEC"1"
ROOM"CPU1"
CDS_LOCATION"R6P39"
SEC"1"
CDS_LIB"mstr_discrete"
SEC_TYPE"0402"
WATTAGE"1/16W"
MATERIAL"CHIP"
PACK_TYPE"0402"
TOLERANCE"1%"
VALUE"4.75K"
PART_NUMBER"G21796-072"
LOCATION"R6P39";
"A"
$PN"1"4;
"B"
$PN"2"102;
%"RES"
"2","(13500,3225)","0","mstr_discrete","I19";
;
CDS_SEC"1"
ROOM"CPU1"
CDS_LOCATION"R3B2"
SEC"1"
BOM_COST"PROC_SOCKET"
SEC_TYPE"0402"
CDS_LIB"mstr_discrete"
WATTAGE"1/16W"
PACK_TYPE"0402"
TOLERANCE"1%"
MATERIAL"CHIP"
VALUE"49.9"
PART_NUMBER"G21796-047"
LOCATION"R3B2";
"A"
$PN"1"111;
"B"
$PN"2"5;
%"RES"
"2","(13300,3225)","0","mstr_discrete","I21";
;
CDS_SEC"1"
ROOM"CPU1"
CDS_LOCATION"R3B4"
SEC"1"
BOM_COST"PROC_SOCKET"
SEC_TYPE"0402"
CDS_LIB"mstr_discrete"
WATTAGE"1/16W"
PACK_TYPE"0402"
TOLERANCE"1%"
MATERIAL"CHIP"
VALUE"100.0"
PART_NUMBER"G21796-017"
LOCATION"R3B4";
"A"
$PN"1"110;
"B"
$PN"2"5;
%"PVCCIO_CPU1"
"1","(13850,3025)","0","mstr_symbols","I22";
;
HDL_POWER"PVCCIO_CPU1"
BODY_TYPE"PLUMBING"
CDS_LIB"mstr_symbols"
VOLTAGE"1.1V";
"G\NAC"5;
%"RES"
"1","(12300,3650)","0","mstr_discrete","I24";
;
ROOM"CPU1"
CDS_LOCATION"R1C2"
$SEC"1"
CDS_SEC"1"
BOM_COST"PROC_SOCKET"
CDS_LIB"mstr_discrete"
WATTAGE"1/16W"
MATERIAL"CHIP"
PACK_TYPE"0402"
TOLERANCE"5%"
VALUE"0.0"
PART_NUMBER"G21497-005"
LOCATION"R1C2";
"B"
$PN"2"113;
"A"
$PN"1"63;
%"RES"
"1","(12300,3600)","0","mstr_discrete","I25";
;
ROOM"CPU1"
CDS_LOCATION"R1C3"
$SEC"1"
CDS_SEC"1"
BOM_COST"PROC_SOCKET"
CDS_LIB"mstr_discrete"
WATTAGE"1/16W"
MATERIAL"CHIP"
PACK_TYPE"0402"
TOLERANCE"5%"
VALUE"0.0"
PART_NUMBER"G21497-005"
LOCATION"R1C3";
"B"
$PN"2"106;
"A"
$PN"1"57;
%"RES"
"1","(12300,3550)","0","mstr_discrete","I26";
;
ROOM"CPU1"
CDS_LOCATION"R1C1"
$SEC"1"
CDS_SEC"1"
BOM_COST"PROC_SOCKET"
CDS_LIB"mstr_discrete"
WATTAGE"1/16W"
MATERIAL"CHIP"
PACK_TYPE"0402"
TOLERANCE"1.0%"
VALUE"221"
PART_NUMBER"G21796-271"
LOCATION"R1C1";
"B"
$PN"2"112;
"A"
$PN"1"58;
%"RES"
"1","(12300,3400)","0","mstr_discrete","I27";
;
ROOM"CPU1"
CDS_LOCATION"R3B1"
$SEC"1"
CDS_SEC"1"
BOM_COST"PROC_SOCKET"
CDS_LIB"mstr_discrete"
WATTAGE"1/16W"
MATERIAL"CHIP"
PACK_TYPE"0402"
TOLERANCE"1.0%"
VALUE"221"
PART_NUMBER"G21796-271"
LOCATION"R3B1";
"B"
$PN"2"111;
"A"
$PN"1"61;
%"RES"
"1","(12300,3450)","0","mstr_discrete","I28";
;
ROOM"CPU1"
CDS_LOCATION"R3B5"
$SEC"1"
CDS_SEC"1"
BOM_COST"PROC_SOCKET"
CDS_LIB"mstr_discrete"
WATTAGE"1/16W"
MATERIAL"CHIP"
PACK_TYPE"0402"
TOLERANCE"5%"
VALUE"0.0"
PART_NUMBER"G21497-005"
LOCATION"R3B5";
"B"
$PN"2"107;
"A"
$PN"1"56;
%"RES"
"1","(12300,3500)","0","mstr_discrete","I29";
;
ROOM"CPU1"
CDS_LOCATION"R3B3"
$SEC"1"
CDS_SEC"1"
BOM_COST"PROC_SOCKET"
CDS_LIB"mstr_discrete"
WATTAGE"1/16W"
MATERIAL"CHIP"
PACK_TYPE"0402"
TOLERANCE"5%"
VALUE"0.0"
PART_NUMBER"G21497-005"
LOCATION"R3B3";
"B"
$PN"2"110;
"A"
$PN"1"60;
%"RES"
"2","(13575,3925)","0","mstr_discrete","I4";
;
CDS_SEC"1"
ROOM"CPU1"
CDS_LOCATION"R9N1"
SEC"1"
BOM_COST"PROC_SOCKET"
SEC_TYPE"0402"
CDS_LIB"mstr_discrete"
WATTAGE"1/16W"
PACK_TYPE"0402"
TOLERANCE"1%"
MATERIAL"CHIP"
VALUE"49.9"
PART_NUMBER"G21796-047"
LOCATION"R9N1";
"A"
$PN"1"6;
"B"
$PN"2"112;
%"PVCCIO_CPU1"
"1","(13325,4275)","0","mstr_symbols","I6";
;
HDL_POWER"PVCCIO_CPU1"
BODY_TYPE"PLUMBING"
CDS_LIB"mstr_symbols"
VOLTAGE"1.1V";
"G\NAC"6;
%"RES"
"2","(13325,3925)","0","mstr_discrete","I7";
;
CDS_SEC"1"
ROOM"CPU1"
CDS_LOCATION"R9N2"
SEC"1"
BOM_COST"PROC_SOCKET"
CDS_LIB"mstr_discrete"
SEC_TYPE"0402"
WATTAGE"1/16W"
PACK_TYPE"0402"
TOLERANCE"1%"
MATERIAL"CHIP"
VALUE"100.0"
PART_NUMBER"G21796-017"
LOCATION"R9N2";
"A"
$PN"1"6;
"B"
$PN"2"113;
END.
